# T6G (Grand Teton) — schematic netlist excerpt (pin names and nets, part order shuffled) for the footprints in the layout excerpt that follows; sources: Cadence DE-HDL packaged netlist, KiCad conversion of 04192023_DAF0TMB3IC0_F0TG_MB_C_brd_V02_OCP.brd

R653  Q_RES  0 5% EMPTY  pkg 0402LF  page 334 : A = P1V8_CPU1_RT1_1A_1D ; B = P1V8_CPU1_RT1_1A
R1320  Q_RES  4.7K 1% CHIP  pkg 0402LF  page 357 : A = P3V3_AUX ; B = INA230_6_A1

(kicad_pcb
	(version 20260206)
	(generator "pcbnew")
	(generator_version "10.0")
	(general
		(thickness 1.6)
		(legacy_teardrops no)
	)
	(paper "A4")
	(title_block
		(title "04192023_DAF0TMB3IC0_F0TG_MB_C_brd_V02_OCP.brd")
		(comment 1 "Grand Teton / footprints 3103-3104 of 8354")
	)
	(layers
		(0 "F.Cu" signal "TOP")
		(4 "In1.Cu" signal "GND")
		(6 "In2.Cu" signal "IN1")
		(8 "In3.Cu" signal "GND1")
		(10 "In4.Cu" signal "IN2")
		(12 "In5.Cu" signal "GND2")
		(14 "In6.Cu" signal "IN3")
		(16 "In7.Cu" signal "GND3")
		(18 "In8.Cu" signal "VCC")
		(20 "In9.Cu" signal "VCC1")
		(22 "In10.Cu" signal "GND4")
		(24 "In11.Cu" signal "IN4")
		(26 "In12.Cu" signal "GND5")
		(28 "In13.Cu" signal "IN5")
		(30 "In14.Cu" signal "GND6")
		(32 "In15.Cu" signal "IN6")
		(34 "In16.Cu" signal "GND7")
		(2 "B.Cu" signal "BOTTOM")
		(9 "F.Adhes" user "F.Adhesive")
		(11 "B.Adhes" user "B.Adhesive")
		(13 "F.Paste" user "Package Geometry/Pastemask Top")
		(15 "B.Paste" user "Package Geometry/Pastemask Bottom")
		(5 "F.SilkS" user "Ref Des/Silkscreen Top")
		(7 "B.SilkS" user "Ref Des/Silkscreen Bottom")
		(1 "F.Mask" user "Board Geometry/Soldermask Top")
		(3 "B.Mask" user "Board Geometry/Soldermask Bottom")
		(17 "Dwgs.User" user "User.Drawings")
		(19 "Cmts.User" user "User.Comments")
		(21 "Eco1.User" user "User.Eco1")
		(23 "Eco2.User" user "User.Eco2")
		(25 "Edge.Cuts" user "Board Geometry/Outline")
		(27 "Margin" user)
		(31 "F.CrtYd" user "Package Geometry/Place Bound Top")
		(29 "B.CrtYd" user "Package Geometry/Place Bound Bottom")
		(35 "F.Fab" user "Ref Des/Assembly Top")
		(33 "B.Fab" user "Ref Des/Assembly Bottom")
	)
	(footprint ""
		(layer "F.Cu")
		(at 102.390194 -384.10388 180)
		(property "Reference" "R653"
			(at 0 0 180)
			(layer "F.SilkS")
			(hide yes)
			(effects
				(font
					(size 1.27 1.27)
				)
			)
		)
		(property "Value" ""
			(at 0 0 180)
			(layer "F.Fab")
			(effects
				(font
					(size 1.27 1.27)
				)
			)
		)
		(duplicate_pad_numbers_are_jumpers no)
		(fp_line
			(start 0.7874 0.4064)
			(end -0.7874 0.4064)
			(stroke
				(width 0.1524)
				(type default)
			)
			(layer "F.SilkS")
		)
		(fp_line
			(start 0.7874 -0.4064)
			(end 0.7874 0.4064)
			(stroke
				(width 0.1524)
				(type default)
			)
			(layer "F.SilkS")
		)
		(fp_line
			(start -0.7874 0.4064)
			(end -0.7874 -0.4064)
			(stroke
				(width 0.1524)
				(type default)
			)
			(layer "F.SilkS")
		)
		(fp_line
			(start -0.7874 -0.4064)
			(end 0.7874 -0.4064)
			(stroke
				(width 0.1524)
				(type default)
			)
			(layer "F.SilkS")
		)
		(fp_line
			(start 0.67945 0.3048)
			(end 0.120396 0.3048)
			(stroke
				(width 0.1)
				(type default)
			)
			(layer "F.Fab")
		)
		(fp_line
			(start 0.67945 -0.3048)
			(end 0.67945 0.3048)
			(stroke
				(width 0.1)
				(type default)
			)
			(layer "F.Fab")
		)
		(fp_line
			(start 0.12065 -0.2794)
			(end 0.12065 -0.3048)
			(stroke
				(width 0.1)
				(type default)
			)
			(layer "F.Fab")
		)
		(fp_line
			(start 0.12065 -0.3048)
			(end 0.67945 -0.3048)
			(stroke
				(width 0.1)
				(type default)
			)
			(layer "F.Fab")
		)
		(fp_line
			(start 0.120396 0.3048)
			(end 0.120396 0.2794)
			(stroke
				(width 0.1)
				(type default)
			)
			(layer "F.Fab")
		)
		(fp_line
			(start 0.120396 0.2794)
			(end -0.12065 0.2794)
			(stroke
				(width 0.1)
				(type default)
			)
			(layer "F.Fab")
		)
		(fp_line
			(start -0.12065 0.3048)
			(end -0.67945 0.3048)
			(stroke
				(width 0.1)
				(type default)
			)
			(layer "F.Fab")
		)
		(fp_line
			(start -0.12065 0.2794)
			(end -0.12065 0.3048)
			(stroke
				(width 0.1)
				(type default)
			)
			(layer "F.Fab")
		)
		(fp_line
			(start -0.12065 -0.2794)
			(end 0.12065 -0.2794)
			(stroke
				(width 0.1)
				(type default)
			)
			(layer "F.Fab")
		)
		(fp_line
			(start -0.12065 -0.305054)
			(end -0.12065 -0.2794)
			(stroke
				(width 0.1)
				(type default)
			)
			(layer "F.Fab")
		)
		(fp_line
			(start -0.67945 0.3048)
			(end -0.67945 -0.305054)
			(stroke
				(width 0.1)
				(type default)
			)
			(layer "F.Fab")
		)
		(fp_line
			(start -0.67945 -0.305054)
			(end -0.12065 -0.305054)
			(stroke
				(width 0.1)
				(type default)
			)
			(layer "F.Fab")
		)
		(pad "1" smd rect
			(at -0.40005 0)
			(size 0.4572 0.508)
			(layers "F.Cu" "F.Mask" "F.Paste")
			(net "P1V8_CPU1_RT1_1A_1D")
		)
		(pad "2" smd rect
			(at 0.40005 0)
			(size 0.4572 0.508)
			(layers "F.Cu" "F.Mask" "F.Paste")
			(net "P1V8_CPU1_RT1_1A")
		)
	)
	(footprint ""
		(layer "F.Cu")
		(at 391.291318 -78.439264)
		(property "Reference" "R1320"
			(at 0 0 0)
			(layer "F.SilkS")
			(hide yes)
			(effects
				(font
					(size 1.27 1.27)
				)
			)
		)
		(property "Value" ""
			(at 0 0 0)
			(layer "F.Fab")
			(effects
				(font
					(size 1.27 1.27)
				)
			)
		)
		(duplicate_pad_numbers_are_jumpers no)
		(fp_line
			(start -0.7874 -0.4064)
			(end 0.7874 -0.4064)
			(stroke
				(width 0.1524)
				(type default)
			)
			(layer "F.SilkS")
		)
		(fp_line
			(start -0.7874 0.4064)
			(end -0.7874 -0.4064)
			(stroke
				(width 0.1524)
				(type default)
			)
			(layer "F.SilkS")
		)
		(fp_line
			(start 0.7874 -0.4064)
			(end 0.7874 0.4064)
			(stroke
				(width 0.1524)
				(type default)
			)
			(layer "F.SilkS")
		)
		(fp_line
			(start 0.7874 0.4064)
			(end -0.7874 0.4064)
			(stroke
				(width 0.1524)
				(type default)
			)
			(layer "F.SilkS")
		)
		(fp_line
			(start -0.67945 -0.305054)
			(end -0.12065 -0.305054)
			(stroke
				(width 0.1)
				(type default)
			)
			(layer "F.Fab")
		)
		(fp_line
			(start -0.67945 0.3048)
			(end -0.67945 -0.305054)
			(stroke
				(width 0.1)
				(type default)
			)
			(layer "F.Fab")
		)
		(fp_line
			(start -0.12065 -0.305054)
			(end -0.12065 -0.2794)
			(stroke
				(width 0.1)
				(type default)
			)
			(layer "F.Fab")
		)
		(fp_line
			(start -0.12065 -0.2794)
			(end 0.12065 -0.2794)
			(stroke
				(width 0.1)
				(type default)
			)
			(layer "F.Fab")
		)
		(fp_line
			(start -0.12065 0.2794)
			(end -0.12065 0.3048)
			(stroke
				(width 0.1)
				(type default)
			)
			(layer "F.Fab")
		)
		(fp_line
			(start -0.12065 0.3048)
			(end -0.67945 0.3048)
			(stroke
				(width 0.1)
				(type default)
			)
			(layer "F.Fab")
		)
		(fp_line
			(start 0.120396 0.2794)
			(end -0.12065 0.2794)
			(stroke
				(width 0.1)
				(type default)
			)
			(layer "F.Fab")
		)
		(fp_line
			(start 0.120396 0.3048)
			(end 0.120396 0.2794)
			(stroke
				(width 0.1)
				(type default)
			)
			(layer "F.Fab")
		)
		(fp_line
			(start 0.12065 -0.3048)
			(end 0.67945 -0.3048)
			(stroke
				(width 0.1)
				(type default)
			)
			(layer "F.Fab")
		)
		(fp_line
			(start 0.12065 -0.2794)
			(end 0.12065 -0.3048)
			(stroke
				(width 0.1)
				(type default)
			)
			(layer "F.Fab")
		)
		(fp_line
			(start 0.67945 -0.3048)
			(end 0.67945 0.3048)
			(stroke
				(width 0.1)
				(type default)
			)
			(layer "F.Fab")
		)
		(fp_line
			(start 0.67945 0.3048)
			(end 0.120396 0.3048)
			(stroke
				(width 0.1)
				(type default)
			)
			(layer "F.Fab")
		)
		(pad "1" smd circle
			(at -0.40005 0)
			(size 0 0)
			(layers "F.Cu" "F.Mask" "F.Paste")
			(net "P3V3_AUX")
		)
		(pad "2" smd circle
			(at 0.40005 0)
			(size 0 0)
			(layers "F.Cu" "F.Mask" "F.Paste")
			(net "INA230_6_A1")
		)
	)
)
